# T6G (Grand Teton) — schematic netlist excerpt (pin names and nets, part order shuffled) for the footprints in the layout excerpt that follows; sources: Cadence DE-HDL packaged netlist, KiCad conversion of 04192023_DAF0TMB3IC0_F0TG_MB_C_brd_V02_OCP.brd

PC2155  Q_CAP  0.047UF 25V 10% X7R  pkg C0402  page 135 : A = P12V_OCP_SS_1 ; B = GND
R967  Q_RES  20K 1% CHIP  pkg 0201LF  page 276 : A = RT_CPU0_P0_ADDR2 ; B = GND
PR3918  Q_RES  2K 0.1% CHIP  pkg 0402LF  page 263 : A = HSC_IMON ; B = AGND_HSC

(kicad_pcb
	(version 20260206)
	(generator "pcbnew")
	(generator_version "10.0")
	(general
		(thickness 1.6)
		(legacy_teardrops no)
	)
	(paper "A4")
	(title_block
		(title "04192023_DAF0TMB3IC0_F0TG_MB_C_brd_V02_OCP.brd")
		(comment 1 "Grand Teton / footprints 52-54 of 8354")
	)
	(layers
		(0 "F.Cu" signal "TOP")
		(4 "In1.Cu" signal "GND")
		(6 "In2.Cu" signal "IN1")
		(8 "In3.Cu" signal "GND1")
		(10 "In4.Cu" signal "IN2")
		(12 "In5.Cu" signal "GND2")
		(14 "In6.Cu" signal "IN3")
		(16 "In7.Cu" signal "GND3")
		(18 "In8.Cu" signal "VCC")
		(20 "In9.Cu" signal "VCC1")
		(22 "In10.Cu" signal "GND4")
		(24 "In11.Cu" signal "IN4")
		(26 "In12.Cu" signal "GND5")
		(28 "In13.Cu" signal "IN5")
		(30 "In14.Cu" signal "GND6")
		(32 "In15.Cu" signal "IN6")
		(34 "In16.Cu" signal "GND7")
		(2 "B.Cu" signal "BOTTOM")
		(9 "F.Adhes" user "F.Adhesive")
		(11 "B.Adhes" user "B.Adhesive")
		(13 "F.Paste" user "Package Geometry/Pastemask Top")
		(15 "B.Paste" user "Package Geometry/Pastemask Bottom")
		(5 "F.SilkS" user "Ref Des/Silkscreen Top")
		(7 "B.SilkS" user "Ref Des/Silkscreen Bottom")
		(1 "F.Mask" user "Board Geometry/Soldermask Top")
		(3 "B.Mask" user "Board Geometry/Soldermask Bottom")
		(17 "Dwgs.User" user "User.Drawings")
		(19 "Cmts.User" user "User.Comments")
		(21 "Eco1.User" user "User.Eco1")
		(23 "Eco2.User" user "User.Eco2")
		(25 "Edge.Cuts" user "Board Geometry/Outline")
		(27 "Margin" user)
		(31 "F.CrtYd" user "Package Geometry/Place Bound Top")
		(29 "B.CrtYd" user "Package Geometry/Place Bound Bottom")
		(35 "F.Fab" user "Ref Des/Assembly Top")
		(33 "B.Fab" user "Ref Des/Assembly Bottom")
	)
	(footprint ""
		(layer "F.Cu")
		(at 441.050172 -32.173418 90)
		(property "Reference" "PC2155"
			(at 0 0 90)
			(layer "F.SilkS")
			(hide yes)
			(effects
				(font
					(size 1.27 1.27)
				)
			)
		)
		(property "Value" ""
			(at 0 0 90)
			(layer "F.Fab")
			(effects
				(font
					(size 1.27 1.27)
				)
			)
		)
		(duplicate_pad_numbers_are_jumpers no)
		(fp_line
			(start 0.7874 -0.4064)
			(end 0.7874 0.4064)
			(stroke
				(width 0.1524)
				(type default)
			)
			(layer "F.SilkS")
		)
		(fp_line
			(start -0.7874 -0.4064)
			(end 0.7874 -0.4064)
			(stroke
				(width 0.1524)
				(type default)
			)
			(layer "F.SilkS")
		)
		(fp_line
			(start 0.7874 0.4064)
			(end -0.7874 0.4064)
			(stroke
				(width 0.1524)
				(type default)
			)
			(layer "F.SilkS")
		)
		(fp_line
			(start -0.7874 0.4064)
			(end -0.7874 -0.4064)
			(stroke
				(width 0.1524)
				(type default)
			)
			(layer "F.SilkS")
		)
		(fp_line
			(start -0.12065 -0.305054)
			(end -0.12065 -0.2794)
			(stroke
				(width 0.1)
				(type default)
			)
			(layer "F.Fab")
		)
		(fp_line
			(start -0.67945 -0.305054)
			(end -0.12065 -0.305054)
			(stroke
				(width 0.1)
				(type default)
			)
			(layer "F.Fab")
		)
		(fp_line
			(start 0.67945 -0.3048)
			(end 0.67945 0.3048)
			(stroke
				(width 0.1)
				(type default)
			)
			(layer "F.Fab")
		)
		(fp_line
			(start 0.12065 -0.3048)
			(end 0.67945 -0.3048)
			(stroke
				(width 0.1)
				(type default)
			)
			(layer "F.Fab")
		)
		(fp_line
			(start 0.12065 -0.2794)
			(end 0.12065 -0.3048)
			(stroke
				(width 0.1)
				(type default)
			)
			(layer "F.Fab")
		)
		(fp_line
			(start -0.12065 -0.2794)
			(end 0.12065 -0.2794)
			(stroke
				(width 0.1)
				(type default)
			)
			(layer "F.Fab")
		)
		(fp_line
			(start 0.120396 0.2794)
			(end -0.12065 0.2794)
			(stroke
				(width 0.1)
				(type default)
			)
			(layer "F.Fab")
		)
		(fp_line
			(start -0.12065 0.2794)
			(end -0.12065 0.3048)
			(stroke
				(width 0.1)
				(type default)
			)
			(layer "F.Fab")
		)
		(fp_line
			(start 0.67945 0.3048)
			(end 0.120396 0.3048)
			(stroke
				(width 0.1)
				(type default)
			)
			(layer "F.Fab")
		)
		(fp_line
			(start 0.120396 0.3048)
			(end 0.120396 0.2794)
			(stroke
				(width 0.1)
				(type default)
			)
			(layer "F.Fab")
		)
		(fp_line
			(start -0.12065 0.3048)
			(end -0.67945 0.3048)
			(stroke
				(width 0.1)
				(type default)
			)
			(layer "F.Fab")
		)
		(fp_line
			(start -0.67945 0.3048)
			(end -0.67945 -0.305054)
			(stroke
				(width 0.1)
				(type default)
			)
			(layer "F.Fab")
		)
		(pad "1" smd circle
			(at -0.40005 0 90)
			(size 0 0)
			(layers "F.Cu" "F.Mask" "F.Paste")
			(net "P12V_OCP_SS_1")
		)
		(pad "2" smd circle
			(at 0.40005 0 90)
			(size 0 0)
			(layers "F.Cu" "F.Mask" "F.Paste")
			(net "GND")
		)
	)
	(footprint ""
		(layer "F.Cu")
		(at 194.2211 -400.998182 180)
		(property "Reference" "PR3918"
			(at 0 0 180)
			(layer "F.SilkS")
			(hide yes)
			(effects
				(font
					(size 1.27 1.27)
				)
			)
		)
		(property "Value" ""
			(at 0 0 180)
			(layer "F.Fab")
			(effects
				(font
					(size 1.27 1.27)
				)
			)
		)
		(duplicate_pad_numbers_are_jumpers no)
		(fp_line
			(start 0.7874 0.4064)
			(end -0.7874 0.4064)
			(stroke
				(width 0.1524)
				(type default)
			)
			(layer "F.SilkS")
		)
		(fp_line
			(start 0.7874 -0.4064)
			(end 0.7874 0.4064)
			(stroke
				(width 0.1524)
				(type default)
			)
			(layer "F.SilkS")
		)
		(fp_line
			(start -0.7874 0.4064)
			(end -0.7874 -0.4064)
			(stroke
				(width 0.1524)
				(type default)
			)
			(layer "F.SilkS")
		)
		(fp_line
			(start -0.7874 -0.4064)
			(end 0.7874 -0.4064)
			(stroke
				(width 0.1524)
				(type default)
			)
			(layer "F.SilkS")
		)
		(fp_line
			(start 0.67945 0.3048)
			(end 0.120396 0.3048)
			(stroke
				(width 0.1)
				(type default)
			)
			(layer "F.Fab")
		)
		(fp_line
			(start 0.67945 -0.3048)
			(end 0.67945 0.3048)
			(stroke
				(width 0.1)
				(type default)
			)
			(layer "F.Fab")
		)
		(fp_line
			(start 0.12065 -0.2794)
			(end 0.12065 -0.3048)
			(stroke
				(width 0.1)
				(type default)
			)
			(layer "F.Fab")
		)
		(fp_line
			(start 0.12065 -0.3048)
			(end 0.67945 -0.3048)
			(stroke
				(width 0.1)
				(type default)
			)
			(layer "F.Fab")
		)
		(fp_line
			(start 0.120396 0.3048)
			(end 0.120396 0.2794)
			(stroke
				(width 0.1)
				(type default)
			)
			(layer "F.Fab")
		)
		(fp_line
			(start 0.120396 0.2794)
			(end -0.12065 0.2794)
			(stroke
				(width 0.1)
				(type default)
			)
			(layer "F.Fab")
		)
		(fp_line
			(start -0.12065 0.3048)
			(end -0.67945 0.3048)
			(stroke
				(width 0.1)
				(type default)
			)
			(layer "F.Fab")
		)
		(fp_line
			(start -0.12065 0.2794)
			(end -0.12065 0.3048)
			(stroke
				(width 0.1)
				(type default)
			)
			(layer "F.Fab")
		)
		(fp_line
			(start -0.12065 -0.2794)
			(end 0.12065 -0.2794)
			(stroke
				(width 0.1)
				(type default)
			)
			(layer "F.Fab")
		)
		(fp_line
			(start -0.12065 -0.305054)
			(end -0.12065 -0.2794)
			(stroke
				(width 0.1)
				(type default)
			)
			(layer "F.Fab")
		)
		(fp_line
			(start -0.67945 0.3048)
			(end -0.67945 -0.305054)
			(stroke
				(width 0.1)
				(type default)
			)
			(layer "F.Fab")
		)
		(fp_line
			(start -0.67945 -0.305054)
			(end -0.12065 -0.305054)
			(stroke
				(width 0.1)
				(type default)
			)
			(layer "F.Fab")
		)
		(pad "1" smd circle
			(at -0.40005 0 180)
			(size 0 0)
			(layers "F.Cu" "F.Mask" "F.Paste")
			(net "HSC_IMON")
		)
		(pad "2" smd circle
			(at 0.40005 0 180)
			(size 0 0)
			(layers "F.Cu" "F.Mask" "F.Paste")
			(net "AGND_HSC")
		)
	)
	(footprint ""
		(layer "F.Cu")
		(at 328.694542 -395.1732 90)
		(property "Reference" "R967"
			(at 0 0 90)
			(layer "F.SilkS")
			(hide yes)
			(effects
				(font
					(size 1.27 1.27)
				)
			)
		)
		(property "Value" ""
			(at 0 0 90)
			(layer "F.Fab")
			(effects
				(font
					(size 1.27 1.27)
				)
			)
		)
		(duplicate_pad_numbers_are_jumpers no)
		(fp_line
			(start 0.32512 -0.175006)
			(end 0.32512 0.175006)
			(stroke
				(width 0.1)
				(type default)
			)
			(layer "F.Fab")
		)
		(fp_line
			(start -0.32512 -0.175006)
			(end 0.32512 -0.175006)
			(stroke
				(width 0.1)
				(type default)
			)
			(layer "F.Fab")
		)
		(fp_line
			(start 0.32512 0.175006)
			(end -0.32512 0.175006)
			(stroke
				(width 0.1)
				(type default)
			)
			(layer "F.Fab")
		)
		(fp_line
			(start -0.32512 0.175006)
			(end -0.32512 -0.175006)
			(stroke
				(width 0.1)
				(type default)
			)
			(layer "F.Fab")
		)
		(pad "1" smd rect
			(at -0.2667 0 90)
			(size 0.3048 0.381)
			(layers "F.Cu" "F.Mask" "F.Paste")
			(net "RT_CPU0_P0_ADDR2")
		)
		(pad "2" smd rect
			(at 0.2667 0 270)
			(size 0.3048 0.381)
			(layers "F.Cu" "F.Mask" "F.Paste")
			(net "GND")
		)
	)
)
